# T6G (Grand Teton) — schematic netlist excerpt (pin names and nets, part order shuffled) for the footprints in the layout excerpt that follows; sources: Cadence DE-HDL packaged netlist, KiCad conversion of 04192023_DAF0TMB3IC0_F0TG_MB_C_brd_V02_OCP.brd

C2019  Q_CAP  0.1UF 25V 10% X7R  pkg 0402  page 237 : A = P12V_SCM_R ; B = GND
R256  Q_RES  0 5% EMPTY  pkg 0402LF  page 160 : A = SMB_CPU0_CPU1_APML_BUF1_SCL_R2 ; B = SMB_CPU0_CPU1_APML_SCL_R2

(kicad_pcb
	(version 20260206)
	(generator "pcbnew")
	(generator_version "10.0")
	(general
		(thickness 1.6)
		(legacy_teardrops no)
	)
	(paper "A4")
	(title_block
		(title "04192023_DAF0TMB3IC0_F0TG_MB_C_brd_V02_OCP.brd")
		(comment 1 "Grand Teton / footprints 8006-8007 of 8354")
	)
	(layers
		(0 "F.Cu" signal "TOP")
		(4 "In1.Cu" signal "GND")
		(6 "In2.Cu" signal "IN1")
		(8 "In3.Cu" signal "GND1")
		(10 "In4.Cu" signal "IN2")
		(12 "In5.Cu" signal "GND2")
		(14 "In6.Cu" signal "IN3")
		(16 "In7.Cu" signal "GND3")
		(18 "In8.Cu" signal "VCC")
		(20 "In9.Cu" signal "VCC1")
		(22 "In10.Cu" signal "GND4")
		(24 "In11.Cu" signal "IN4")
		(26 "In12.Cu" signal "GND5")
		(28 "In13.Cu" signal "IN5")
		(30 "In14.Cu" signal "GND6")
		(32 "In15.Cu" signal "IN6")
		(34 "In16.Cu" signal "GND7")
		(2 "B.Cu" signal "BOTTOM")
		(9 "F.Adhes" user "F.Adhesive")
		(11 "B.Adhes" user "B.Adhesive")
		(13 "F.Paste" user "Package Geometry/Pastemask Top")
		(15 "B.Paste" user "Package Geometry/Pastemask Bottom")
		(5 "F.SilkS" user "Ref Des/Silkscreen Top")
		(7 "B.SilkS" user "Ref Des/Silkscreen Bottom")
		(1 "F.Mask" user "Board Geometry/Soldermask Top")
		(3 "B.Mask" user "Board Geometry/Soldermask Bottom")
		(17 "Dwgs.User" user "User.Drawings")
		(19 "Cmts.User" user "User.Comments")
		(21 "Eco1.User" user "User.Eco1")
		(23 "Eco2.User" user "User.Eco2")
		(25 "Edge.Cuts" user "Board Geometry/Outline")
		(27 "Margin" user)
		(31 "F.CrtYd" user "Package Geometry/Place Bound Top")
		(29 "B.CrtYd" user "Package Geometry/Place Bound Bottom")
		(35 "F.Fab" user "Ref Des/Assembly Top")
		(33 "B.Fab" user "Ref Des/Assembly Bottom")
	)
	(footprint ""
		(layer "B.Cu")
		(at 235.1151 -215.186514)
		(property "Reference" "R256"
			(at 0 0 0)
			(layer "B.SilkS")
			(hide yes)
			(effects
				(font
					(size 1.27 1.27)
				)
				(justify mirror)
			)
		)
		(property "Value" ""
			(at 0 0 0)
			(layer "B.Fab")
			(effects
				(font
					(size 1.27 1.27)
				)
				(justify mirror)
			)
		)
		(duplicate_pad_numbers_are_jumpers no)
		(fp_line
			(start -0.7874 -0.4064)
			(end -0.7874 0.4064)
			(stroke
				(width 0.1524)
				(type default)
			)
			(layer "B.SilkS")
		)
		(fp_line
			(start -0.7874 0.4064)
			(end 0.7874 0.4064)
			(stroke
				(width 0.1524)
				(type default)
			)
			(layer "B.SilkS")
		)
		(fp_line
			(start 0.7874 -0.4064)
			(end -0.7874 -0.4064)
			(stroke
				(width 0.1524)
				(type default)
			)
			(layer "B.SilkS")
		)
		(fp_line
			(start 0.7874 0.4064)
			(end 0.7874 -0.4064)
			(stroke
				(width 0.1524)
				(type default)
			)
			(layer "B.SilkS")
		)
		(fp_line
			(start -0.67945 -0.3048)
			(end -0.67945 0.3048)
			(stroke
				(width 0.1)
				(type default)
			)
			(layer "B.Fab")
		)
		(fp_line
			(start -0.67945 0.3048)
			(end -0.120396 0.3048)
			(stroke
				(width 0.1)
				(type default)
			)
			(layer "B.Fab")
		)
		(fp_line
			(start -0.12065 -0.3048)
			(end -0.67945 -0.3048)
			(stroke
				(width 0.1)
				(type default)
			)
			(layer "B.Fab")
		)
		(fp_line
			(start -0.12065 -0.2794)
			(end -0.12065 -0.3048)
			(stroke
				(width 0.1)
				(type default)
			)
			(layer "B.Fab")
		)
		(fp_line
			(start -0.120396 0.2794)
			(end 0.12065 0.2794)
			(stroke
				(width 0.1)
				(type default)
			)
			(layer "B.Fab")
		)
		(fp_line
			(start -0.120396 0.3048)
			(end -0.120396 0.2794)
			(stroke
				(width 0.1)
				(type default)
			)
			(layer "B.Fab")
		)
		(fp_line
			(start 0.12065 -0.305054)
			(end 0.12065 -0.2794)
			(stroke
				(width 0.1)
				(type default)
			)
			(layer "B.Fab")
		)
		(fp_line
			(start 0.12065 -0.2794)
			(end -0.12065 -0.2794)
			(stroke
				(width 0.1)
				(type default)
			)
			(layer "B.Fab")
		)
		(fp_line
			(start 0.12065 0.2794)
			(end 0.12065 0.3048)
			(stroke
				(width 0.1)
				(type default)
			)
			(layer "B.Fab")
		)
		(fp_line
			(start 0.12065 0.3048)
			(end 0.67945 0.3048)
			(stroke
				(width 0.1)
				(type default)
			)
			(layer "B.Fab")
		)
		(fp_line
			(start 0.67945 -0.305054)
			(end 0.12065 -0.305054)
			(stroke
				(width 0.1)
				(type default)
			)
			(layer "B.Fab")
		)
		(fp_line
			(start 0.67945 0.3048)
			(end 0.67945 -0.305054)
			(stroke
				(width 0.1)
				(type default)
			)
			(layer "B.Fab")
		)
		(pad "1" smd rect
			(at 0.40005 0)
			(size 0.4572 0.508)
			(layers "B.Cu" "B.Mask" "B.Paste")
			(net "SMB_CPU0_CPU1_APML_BUF1_SCL_R2")
		)
		(pad "2" smd rect
			(at -0.40005 0)
			(size 0.4572 0.508)
			(layers "B.Cu" "B.Mask" "B.Paste")
			(net "SMB_CPU0_CPU1_APML_SCL_R2")
		)
	)
	(footprint ""
		(layer "B.Cu")
		(at 208.56448 -35.804348 90)
		(property "Reference" "C2019"
			(at 0 0 90)
			(layer "B.SilkS")
			(hide yes)
			(effects
				(font
					(size 1.27 1.27)
				)
				(justify mirror)
			)
		)
		(property "Value" ""
			(at 0 0 90)
			(layer "B.Fab")
			(effects
				(font
					(size 1.27 1.27)
				)
				(justify mirror)
			)
		)
		(duplicate_pad_numbers_are_jumpers no)
		(fp_line
			(start 0.7874 -0.4064)
			(end -0.7874 -0.4064)
			(stroke
				(width 0.1524)
				(type default)
			)
			(layer "B.SilkS")
		)
		(fp_line
			(start -0.7874 -0.4064)
			(end -0.7874 0.4064)
			(stroke
				(width 0.1524)
				(type default)
			)
			(layer "B.SilkS")
		)
		(fp_line
			(start 0.7874 0.4064)
			(end 0.7874 -0.4064)
			(stroke
				(width 0.1524)
				(type default)
			)
			(layer "B.SilkS")
		)
		(fp_line
			(start -0.7874 0.4064)
			(end 0.7874 0.4064)
			(stroke
				(width 0.1524)
				(type default)
			)
			(layer "B.SilkS")
		)
		(fp_line
			(start 0.67945 -0.305054)
			(end 0.12065 -0.305054)
			(stroke
				(width 0.1)
				(type default)
			)
			(layer "B.Fab")
		)
		(fp_line
			(start 0.12065 -0.305054)
			(end 0.12065 -0.2794)
			(stroke
				(width 0.1)
				(type default)
			)
			(layer "B.Fab")
		)
		(fp_line
			(start -0.12065 -0.3048)
			(end -0.67945 -0.3048)
			(stroke
				(width 0.1)
				(type default)
			)
			(layer "B.Fab")
		)
		(fp_line
			(start -0.67945 -0.3048)
			(end -0.67945 0.3048)
			(stroke
				(width 0.1)
				(type default)
			)
			(layer "B.Fab")
		)
		(fp_line
			(start 0.12065 -0.2794)
			(end -0.12065 -0.2794)
			(stroke
				(width 0.1)
				(type default)
			)
			(layer "B.Fab")
		)
		(fp_line
			(start -0.12065 -0.2794)
			(end -0.12065 -0.3048)
			(stroke
				(width 0.1)
				(type default)
			)
			(layer "B.Fab")
		)
		(fp_line
			(start 0.12065 0.2794)
			(end 0.12065 0.3048)
			(stroke
				(width 0.1)
				(type default)
			)
			(layer "B.Fab")
		)
		(fp_line
			(start -0.120396 0.2794)
			(end 0.12065 0.2794)
			(stroke
				(width 0.1)
				(type default)
			)
			(layer "B.Fab")
		)
		(fp_line
			(start 0.67945 0.3048)
			(end 0.67945 -0.305054)
			(stroke
				(width 0.1)
				(type default)
			)
			(layer "B.Fab")
		)
		(fp_line
			(start 0.12065 0.3048)
			(end 0.67945 0.3048)
			(stroke
				(width 0.1)
				(type default)
			)
			(layer "B.Fab")
		)
		(fp_line
			(start -0.120396 0.3048)
			(end -0.120396 0.2794)
			(stroke
				(width 0.1)
				(type default)
			)
			(layer "B.Fab")
		)
		(fp_line
			(start -0.67945 0.3048)
			(end -0.120396 0.3048)
			(stroke
				(width 0.1)
				(type default)
			)
			(layer "B.Fab")
		)
		(pad "1" smd circle
			(at 0.40005 0 270)
			(size 0 0)
			(layers "B.Cu" "B.Mask" "B.Paste")
			(net "P12V_SCM_R")
		)
		(pad "2" smd circle
			(at -0.40005 0 270)
			(size 0 0)
			(layers "B.Cu" "B.Mask" "B.Paste")
			(net "GND")
		)
	)
)
